(kicad_pcb
	(version 20260206)
	(generator "pcbnew")
	(generator_version "10.0")
	(general
		(thickness 1.6)
		(legacy_teardrops no)
	)
	(paper "A4")
	(title_block
		(title "Wiwynn_Tioga_Pass_MB.brd")
		(comment 1 "Tioga Pass / footprints 1440-1440 of 4770")
	)
	(layers
		(0 "F.Cu" signal "TOP")
		(4 "In1.Cu" signal "L2GND")
		(6 "In2.Cu" signal "L3")
		(8 "In3.Cu" signal "L4GND")
		(10 "In4.Cu" signal "L5")
		(12 "In5.Cu" signal "L6GND")
		(14 "In6.Cu" signal "L7VCC")
		(16 "In7.Cu" signal "L8VCC")
		(18 "In8.Cu" signal "L9GND")
		(20 "In9.Cu" signal "L10")
		(22 "In10.Cu" signal "L11GND")
		(24 "In11.Cu" signal "L12")
		(26 "In12.Cu" signal "L13GND")
		(2 "B.Cu" signal "BOTTOM")
		(9 "F.Adhes" user "F.Adhesive")
		(11 "B.Adhes" user "B.Adhesive")
		(13 "F.Paste" user "Package Geometry/Pastemask Top")
		(15 "B.Paste" user "Package Geometry/Pastemask Bottom")
		(5 "F.SilkS" user "Ref Des/Silkscreen Top")
		(7 "B.SilkS" user "Ref Des/Silkscreen Bottom")
		(1 "F.Mask" user "Board Geometry/Soldermask Top")
		(3 "B.Mask" user "Board Geometry/Soldermask Bottom")
		(17 "Dwgs.User" user "User.Drawings")
		(19 "Cmts.User" user "User.Comments")
		(21 "Eco1.User" user "User.Eco1")
		(23 "Eco2.User" user "User.Eco2")
		(25 "Edge.Cuts" user "Board Geometry/Outline")
		(27 "Margin" user)
		(31 "F.CrtYd" user "Package Geometry/Place Bound Top")
		(29 "B.CrtYd" user "Package Geometry/Place Bound Bottom")
		(35 "F.Fab" user "Ref Des/Assembly Top")
		(33 "B.Fab" user "Ref Des/Assembly Bottom")
	)
	(footprint ""
		(layer "F.Cu")
		(at 271.898872 -73.279)
		(property "Reference" "C5D53"
			(at 0 0 0)
			(layer "F.SilkS")
			(hide yes)
			(effects
				(font
					(size 1.27 1.27)
				)
			)
		)
		(property "Value" ""
			(at 0 0 0)
			(layer "F.Fab")
			(effects
				(font
					(size 1.27 1.27)
				)
			)
		)
		(duplicate_pad_numbers_are_jumpers no)
		(fp_poly
			(pts
				(xy -0.4953 -0.2032) (xy 0.4953 -0.2032) (xy 0.4953 1.6002) (xy -0.4953 1.6002)
			)
			(stroke
				(width 0)
				(type default)
			)
			(fill no)
			(layer "F.CrtYd")
		)
		(fp_line
			(start -0.4953 -0.2032)
			(end 0.4953 -0.2032)
			(stroke
				(width 0.1)
				(type default)
			)
			(layer "F.Fab")
		)
		(fp_line
			(start -0.4953 1.6002)
			(end -0.4953 -0.2032)
			(stroke
				(width 0.1)
				(type default)
			)
			(layer "F.Fab")
		)
		(fp_line
			(start 0.4953 -0.2032)
			(end 0.4953 1.6002)
			(stroke
				(width 0.1)
				(type default)
			)
			(layer "F.Fab")
		)
		(fp_line
			(start 0.4953 1.6002)
			(end -0.4953 1.6002)
			(stroke
				(width 0.1)
				(type default)
			)
			(layer "F.Fab")
		)
		(pad "1" smd rect
			(at 0 0)
			(size 0.762 0.889)
			(layers "F.Cu" "F.Mask" "F.Paste")
			(net "PVCCMCP_CPU0")
		)
		(pad "2" smd rect
			(at 0 1.397)
			(size 0.762 0.889)
			(layers "F.Cu" "F.Mask" "F.Paste")
			(net "GND")
		)
		(zone
			(layer "F.Cu")
			(hatch none 0.5)
			(connect_pads
				(clearance 0)
			)
			(min_thickness 0.25)
			(keepout
				(tracks not_allowed)
				(vias allowed)
				(pads allowed)
				(copperpour not_allowed)
				(footprints allowed)
			)
			(placement
				(enabled no)
				(sheetname "")
			)
			(fill
				(thermal_gap 0.5)
				(thermal_bridge_width 0.5)
				(island_removal_mode 0)
			)
			(polygon
				(pts
					(xy 271.517872 -72.8345) (xy 272.279872 -72.8345) (xy 272.279872 -72.3265) (xy 271.517872 -72.3265)
				)
			)
		)
	)
)
